(kicad_pcb
	(version 20260206)
	(generator "pcbnew")
	(generator_version "10.0")
	(general
		(thickness 1.6)
		(legacy_teardrops no)
	)
	(paper "A4")
	(title_block
		(title "Wiwynn_Tioga_Pass_MB.brd")
		(comment 1 "Tioga Pass / footprint 2254 of 4770 (U5D1), pads 627-728 of 3647")
	)
	(layers
		(0 "F.Cu" signal "TOP")
		(4 "In1.Cu" signal "L2GND")
		(6 "In2.Cu" signal "L3")
		(8 "In3.Cu" signal "L4GND")
		(10 "In4.Cu" signal "L5")
		(12 "In5.Cu" signal "L6GND")
		(14 "In6.Cu" signal "L7VCC")
		(16 "In7.Cu" signal "L8VCC")
		(18 "In8.Cu" signal "L9GND")
		(20 "In9.Cu" signal "L10")
		(22 "In10.Cu" signal "L11GND")
		(24 "In11.Cu" signal "L12")
		(26 "In12.Cu" signal "L13GND")
		(2 "B.Cu" signal "BOTTOM")
		(9 "F.Adhes" user "F.Adhesive")
		(11 "B.Adhes" user "B.Adhesive")
		(13 "F.Paste" user "Package Geometry/Pastemask Top")
		(15 "B.Paste" user "Package Geometry/Pastemask Bottom")
		(5 "F.SilkS" user "Ref Des/Silkscreen Top")
		(7 "B.SilkS" user "Ref Des/Silkscreen Bottom")
		(1 "F.Mask" user "Board Geometry/Soldermask Top")
		(3 "B.Mask" user "Board Geometry/Soldermask Bottom")
		(17 "Dwgs.User" user "User.Drawings")
		(19 "Cmts.User" user "User.Comments")
		(21 "Eco1.User" user "User.Eco1")
		(23 "Eco2.User" user "User.Eco2")
		(25 "Edge.Cuts" user "Board Geometry/Outline")
		(27 "Margin" user)
		(31 "F.CrtYd" user "Package Geometry/Place Bound Top")
		(29 "B.CrtYd" user "Package Geometry/Place Bound Bottom")
		(35 "F.Fab" user "Ref Des/Assembly Top")
		(33 "B.Fab" user "Ref Des/Assembly Bottom")
	)
	(footprint ""
		(layer "F.Cu")
		(at 270.000222 -76.550012 180)
		(property "Reference" "U5D1"
			(at 19.124422 31.601918 0)
			(unlocked yes)
			(layer "F.SilkS")
			(effects
				(font
					(size 0.7874 0.5842)
					(thickness 0.1524)
				)
			)
		)
		(property "Value" ""
			(at 0 0 180)
			(layer "F.Fab")
			(effects
				(font
					(size 1.27 1.27)
				)
			)
		)
		(duplicate_pad_numbers_are_jumpers no)
		(pad "AU26" smd circle
			(at -15.787878 -7.272274)
			(size 0.4318 0.4318)
			(layers "F.Cu" "F.Mask" "F.Paste")
			(net "GND")
		)
		(pad "AU28" smd circle
			(at -14.071092 -7.272274)
			(size 0.4318 0.4318)
			(layers "F.Cu" "F.Mask" "F.Paste")
			(net "GND")
		)
		(pad "AU58" smd circle
			(at 13.212572 -9.072372)
			(size 0.508 0.508)
			(layers "F.Cu" "F.Mask" "F.Paste")
			(net "PVCCIN_CPU0")
		)
		(pad "AU60" smd circle
			(at 14.929612 -9.072372)
			(size 0.4318 0.4318)
			(layers "F.Cu" "F.Mask" "F.Paste")
			(net "PVCCIN_CPU0")
		)
		(pad "AU62" smd circle
			(at 16.646398 -9.072372)
			(size 0.4318 0.4318)
			(layers "F.Cu" "F.Mask" "F.Paste")
			(net "GND")
		)
		(pad "AU64" smd circle
			(at 18.363438 -9.072372)
			(size 0.4318 0.4318)
			(layers "F.Cu" "F.Mask" "F.Paste")
			(net "GND")
		)
		(pad "AU66" smd circle
			(at 20.080478 -9.072372)
			(size 0.4318 0.4318)
			(layers "F.Cu" "F.Mask" "F.Paste")
			(net "M_C_DQS_DN<3>")
		)
		(pad "AU68" smd circle
			(at 21.797518 -9.072372)
			(size 0.4318 0.4318)
			(layers "F.Cu" "F.Mask" "F.Paste")
			(net "GND")
		)
		(pad "AU70" smd circle
			(at 23.514558 -9.072372)
			(size 0.4318 0.4318)
			(layers "F.Cu" "F.Mask" "F.Paste")
			(net "M_C_ECC<6>")
		)
		(pad "AU72" smd circle
			(at 25.231598 -9.072372)
			(size 0.4318 0.4318)
			(layers "F.Cu" "F.Mask" "F.Paste")
			(net "M_C_ECC<0>")
		)
		(pad "AU74" smd circle
			(at 26.948384 -9.072372)
			(size 0.4318 0.4318)
			(layers "F.Cu" "F.Mask" "F.Paste")
			(net "GND")
		)
		(pad "AU76" smd circle
			(at 28.665424 -9.072372)
			(size 0.4318 0.4318)
			(layers "F.Cu" "F.Mask" "F.Paste")
			(net "GND")
		)
		(pad "AU78" smd circle
			(at 30.382464 -9.072372)
			(size 0.4318 0.4318)
			(layers "F.Cu" "F.Mask" "F.Paste")
			(net "GND")
		)
		(pad "AU80" smd circle
			(at 32.099504 -9.072372)
			(size 0.4318 0.4318)
			(layers "F.Cu" "F.Mask" "F.Paste")
			(net "GND")
		)
		(pad "AU82" smd circle
			(at 33.816544 -9.072372)
			(size 0.4318 0.4318)
			(layers "F.Cu" "F.Mask" "F.Paste")
			(net "M_B_DQS_DN<9>")
		)
		(pad "AU84" smd circle
			(at 35.533584 -9.072372)
			(size 0.4318 0.4318)
			(layers "F.Cu" "F.Mask" "F.Paste")
			(net "GND")
		)
		(pad "AU86" smd custom
			(at 37.250624 -9.072372 270)
			(size 0.10795 0.10795)
			(layers "F.Cu" "F.Mask" "F.Paste")
			(net "GND")
			(options
				(clearance outline)
				(anchor circle)
			)
			(primitives
				(gr_poly
					(pts
						(arc
							(start 0.2159 -0.0381)
							(mid 0 -0.254)
							(end -0.2159 -0.0381)
						)
						(arc
							(start -0.2159 0.0381)
							(mid 0 0.254)
							(end 0.2159 0.0381)
						)
					)
					(width 0)
					(fill yes)
				)
			)
		)
		(pad "AV1" smd custom
			(at -37.250624 -6.777228 90)
			(size 0.10795 0.10795)
			(layers "F.Cu" "F.Mask" "F.Paste")
			(net "GND")
			(options
				(clearance outline)
				(anchor circle)
			)
			(primitives
				(gr_poly
					(pts
						(arc
							(start 0.2159 -0.0381)
							(mid 0 -0.254)
							(end -0.2159 -0.0381)
						)
						(arc
							(start -0.2159 0.0381)
							(mid 0 0.254)
							(end 0.2159 0.0381)
						)
					)
					(width 0)
					(fill yes)
				)
			)
		)
		(pad "AV3" smd circle
			(at -35.533584 -6.777228)
			(size 0.4318 0.4318)
			(layers "F.Cu" "F.Mask" "F.Paste")
			(net "GND")
		)
		(pad "AV5" smd circle
			(at -33.816544 -6.777228)
			(size 0.4318 0.4318)
			(layers "F.Cu" "F.Mask" "F.Paste")
			(net "UPI_CPU0_CPU1_P0P0_DN<4>")
		)
		(pad "AV7" smd circle
			(at -32.099504 -6.777228)
			(size 0.4318 0.4318)
			(layers "F.Cu" "F.Mask" "F.Paste")
			(net "GND")
		)
		(pad "AV9" smd circle
			(at -30.382464 -6.777228)
			(size 0.4318 0.4318)
			(layers "F.Cu" "F.Mask" "F.Paste")
			(net "UPI_CPU1_CPU0_P0P0_DP<3>")
		)
		(pad "AV11" smd circle
			(at -28.665424 -6.777228)
			(size 0.4318 0.4318)
			(layers "F.Cu" "F.Mask" "F.Paste")
			(net "GND")
		)
		(pad "AV13" smd circle
			(at -26.948384 -6.777228)
			(size 0.4318 0.4318)
			(layers "F.Cu" "F.Mask" "F.Paste")
			(net "GND")
		)
		(pad "AV15" smd circle
			(at -25.231598 -6.777228)
			(size 0.4318 0.4318)
			(layers "F.Cu" "F.Mask" "F.Paste")
			(net "PD_CPU0_TXT_PLTEN")
		)
		(pad "AV17" smd circle
			(at -23.514558 -6.777228)
			(size 0.4318 0.4318)
			(layers "F.Cu" "F.Mask" "F.Paste")
			(net "PU_CPU0_FRMAGENT")
		)
		(pad "AV19" smd circle
			(at -21.797518 -6.777228)
			(size 0.4318 0.4318)
			(layers "F.Cu" "F.Mask" "F.Paste")
			(net "GND")
		)
		(pad "AV21" smd circle
			(at -20.080478 -6.777228)
			(size 0.4318 0.4318)
			(layers "F.Cu" "F.Mask" "F.Paste")
			(net "CPU_XDP_PRESENT_N")
		)
		(pad "AV23" smd circle
			(at -18.363438 -6.777228)
			(size 0.4318 0.4318)
			(layers "F.Cu" "F.Mask" "F.Paste")
			(net "GND")
		)
		(pad "AV25" smd circle
			(at -16.646398 -6.777228)
			(size 0.4318 0.4318)
			(layers "F.Cu" "F.Mask" "F.Paste")
			(net "GND")
		)
		(pad "AV27" smd circle
			(at -14.929612 -6.777228)
			(size 0.4318 0.4318)
			(layers "F.Cu" "F.Mask" "F.Paste")
			(net "PVCCIO_CPU0")
		)
		(pad "AV59" smd circle
			(at 14.071092 -8.577326)
			(size 0.508 0.508)
			(layers "F.Cu" "F.Mask" "F.Paste")
			(net "PVCCIN_CPU0")
		)
		(pad "AV61" smd circle
			(at 15.787878 -8.577326)
			(size 0.4318 0.4318)
			(layers "F.Cu" "F.Mask" "F.Paste")
			(net "PVCCIN_CPU0")
		)
		(pad "AV63" smd circle
			(at 17.504918 -8.577326)
			(size 0.4318 0.4318)
			(layers "F.Cu" "F.Mask" "F.Paste")
			(net "GND")
		)
		(pad "AV65" smd circle
			(at 19.221958 -8.577326)
			(size 0.4318 0.4318)
			(layers "F.Cu" "F.Mask" "F.Paste")
			(net "GND")
		)
		(pad "AV67" smd circle
			(at 20.938998 -8.577326)
			(size 0.4318 0.4318)
			(layers "F.Cu" "F.Mask" "F.Paste")
			(net "GND")
		)
		(pad "AV69" smd circle
			(at 22.656038 -8.577326)
			(size 0.4318 0.4318)
			(layers "F.Cu" "F.Mask" "F.Paste")
			(net "M_C_ECC<2>")
		)
		(pad "AV71" smd circle
			(at 24.373078 -8.577326)
			(size 0.4318 0.4318)
			(layers "F.Cu" "F.Mask" "F.Paste")
			(net "M_C_DQS_DP<17>")
		)
		(pad "AV73" smd circle
			(at 26.090118 -8.577326)
			(size 0.4318 0.4318)
			(layers "F.Cu" "F.Mask" "F.Paste")
			(net "M_C_ECC<4>")
		)
		(pad "AV75" smd circle
			(at 27.806904 -8.577326)
			(size 0.4318 0.4318)
			(layers "F.Cu" "F.Mask" "F.Paste")
			(net "GND")
		)
		(pad "AV77" smd circle
			(at 29.523944 -8.577326)
			(size 0.4318 0.4318)
			(layers "F.Cu" "F.Mask" "F.Paste")
			(net "TP_CPU0_RSVD_186")
		)
		(pad "AV79" smd circle
			(at 31.240984 -8.577326)
			(size 0.4318 0.4318)
			(layers "F.Cu" "F.Mask" "F.Paste")
			(net "M_B_DQ<5>")
		)
		(pad "AV81" smd circle
			(at 32.958024 -8.577326)
			(size 0.4318 0.4318)
			(layers "F.Cu" "F.Mask" "F.Paste")
			(net "M_B_DQ<0>")
		)
		(pad "AV83" smd circle
			(at 34.675064 -8.577326)
			(size 0.4318 0.4318)
			(layers "F.Cu" "F.Mask" "F.Paste")
			(net "GND")
		)
		(pad "AV85" smd circle
			(at 36.392104 -8.577326)
			(size 0.4318 0.4318)
			(layers "F.Cu" "F.Mask" "F.Paste")
			(net "VSENSE_VCCINR2PMAX_CPU0")
		)
		(pad "AW2" smd custom
			(at -36.392104 -6.281928 90)
			(size 0.10795 0.10795)
			(layers "F.Cu" "F.Mask" "F.Paste")
			(net "GND")
			(options
				(clearance outline)
				(anchor circle)
			)
			(primitives
				(gr_poly
					(pts
						(arc
							(start 0.2159 -0.0381)
							(mid 0 -0.254)
							(end -0.2159 -0.0381)
						)
						(arc
							(start -0.2159 0.0381)
							(mid 0 0.254)
							(end 0.2159 0.0381)
						)
					)
					(width 0)
					(fill yes)
				)
			)
		)
		(pad "AW4" smd circle
			(at -34.675064 -6.281928)
			(size 0.4318 0.4318)
			(layers "F.Cu" "F.Mask" "F.Paste")
			(net "UPI_CPU0_CPU1_P0P0_DP<4>")
		)
		(pad "AW6" smd circle
			(at -32.958024 -6.281928)
			(size 0.4318 0.4318)
			(layers "F.Cu" "F.Mask" "F.Paste")
			(net "PVCCIO_CPU0")
		)
		(pad "AW8" smd circle
			(at -31.240984 -6.281928)
			(size 0.4318 0.4318)
			(layers "F.Cu" "F.Mask" "F.Paste")
			(net "UPI_CPU1_CPU0_P0P0_DN<3>")
		)
		(pad "AW10" smd circle
			(at -29.523944 -6.281928)
			(size 0.4318 0.4318)
			(layers "F.Cu" "F.Mask" "F.Paste")
			(net "GND")
		)
		(pad "AW12" smd circle
			(at -27.806904 -6.281928)
			(size 0.4318 0.4318)
			(layers "F.Cu" "F.Mask" "F.Paste")
			(net "PD_CPU0_DMIMODE_OVERRIDE")
		)
		(pad "AW14" smd circle
			(at -26.090118 -6.281928)
			(size 0.4318 0.4318)
			(layers "F.Cu" "F.Mask" "F.Paste")
			(net "PD_CPU0_KSFC_DIS")
		)
		(pad "AW16" smd circle
			(at -24.373078 -6.281928)
			(size 0.4318 0.4318)
			(layers "F.Cu" "F.Mask" "F.Paste")
			(net "TP_CPU0_TEST_8")
		)
		(pad "AW18" smd circle
			(at -22.656038 -6.281928)
			(size 0.4318 0.4318)
			(layers "F.Cu" "F.Mask" "F.Paste")
			(net "PU_CPU0_TXT_AGENT")
		)
		(pad "AW20" smd circle
			(at -20.938998 -6.281928)
			(size 0.4318 0.4318)
			(layers "F.Cu" "F.Mask" "F.Paste")
			(net "TP_CPU0_TEST_9")
		)
		(pad "AW22" smd circle
			(at -19.221958 -6.281928)
			(size 0.4318 0.4318)
			(layers "F.Cu" "F.Mask" "F.Paste")
			(net "TP_CPU0_TEST_10")
		)
		(pad "AW24" smd circle
			(at -17.504918 -6.281928)
			(size 0.4318 0.4318)
			(layers "F.Cu" "F.Mask" "F.Paste")
			(net "CLK_100M_CPU0_BCLK0_DP")
		)
		(pad "AW26" smd circle
			(at -15.787878 -6.281928)
			(size 0.4318 0.4318)
			(layers "F.Cu" "F.Mask" "F.Paste")
			(net "PVCCIO_CPU0")
		)
		(pad "AW60" smd circle
			(at 14.929612 -8.081772)
			(size 0.508 0.508)
			(layers "F.Cu" "F.Mask" "F.Paste")
			(net "PVCCIN_CPU0")
		)
		(pad "AW62" smd circle
			(at 16.646398 -8.081772)
			(size 0.4318 0.4318)
			(layers "F.Cu" "F.Mask" "F.Paste")
			(net "GND")
		)
		(pad "AW64" smd circle
			(at 18.363438 -8.081772)
			(size 0.4318 0.4318)
			(layers "F.Cu" "F.Mask" "F.Paste")
			(net "TP_CPU0_RSVD_184")
		)
		(pad "AW66" smd circle
			(at 20.080478 -8.081772)
			(size 0.4318 0.4318)
			(layers "F.Cu" "F.Mask" "F.Paste")
			(net "GND")
		)
		(pad "AW68" smd circle
			(at 21.797518 -8.081772)
			(size 0.4318 0.4318)
			(layers "F.Cu" "F.Mask" "F.Paste")
			(net "GND")
		)
		(pad "AW70" smd circle
			(at 23.514558 -8.081772)
			(size 0.4318 0.4318)
			(layers "F.Cu" "F.Mask" "F.Paste")
			(net "GND")
		)
		(pad "AW72" smd circle
			(at 25.231598 -8.081772)
			(size 0.4318 0.4318)
			(layers "F.Cu" "F.Mask" "F.Paste")
			(net "GND")
		)
		(pad "AW74" smd circle
			(at 26.948384 -8.081772)
			(size 0.4318 0.4318)
			(layers "F.Cu" "F.Mask" "F.Paste")
			(net "GND")
		)
		(pad "AW76" smd circle
			(at 28.665424 -8.081772)
			(size 0.4318 0.4318)
			(layers "F.Cu" "F.Mask" "F.Paste")
			(net "TP_CPU0_RSVD_183")
		)
		(pad "AW78" smd circle
			(at 30.382464 -8.081772)
			(size 0.4318 0.4318)
			(layers "F.Cu" "F.Mask" "F.Paste")
			(net "GND")
		)
		(pad "AW80" smd circle
			(at 32.099504 -8.081772)
			(size 0.4318 0.4318)
			(layers "F.Cu" "F.Mask" "F.Paste")
			(net "M_B_DQ<4>")
		)
		(pad "AW82" smd circle
			(at 33.816544 -8.081772)
			(size 0.4318 0.4318)
			(layers "F.Cu" "F.Mask" "F.Paste")
			(net "GND")
		)
		(pad "AW84" smd circle
			(at 35.533584 -8.081772)
			(size 0.4318 0.4318)
			(layers "F.Cu" "F.Mask" "F.Paste")
			(net "GND")
		)
		(pad "AW86" smd custom
			(at 37.250624 -8.081772 270)
			(size 0.10795 0.10795)
			(layers "F.Cu" "F.Mask" "F.Paste")
			(net "VSENSE_VCCINR2PMAX_CPU0")
			(options
				(clearance outline)
				(anchor circle)
			)
			(primitives
				(gr_poly
					(pts
						(arc
							(start 0.2159 -0.0381)
							(mid 0 -0.254)
							(end -0.2159 -0.0381)
						)
						(arc
							(start -0.2159 0.0381)
							(mid 0 0.254)
							(end 0.2159 0.0381)
						)
					)
					(width 0)
					(fill yes)
				)
			)
		)
		(pad "AY3" smd circle
			(at -35.533584 -5.786628)
			(size 0.4318 0.4318)
			(layers "F.Cu" "F.Mask" "F.Paste")
			(net "UPI_CPU0_CPU1_P0P0_DP<3>")
		)
		(pad "AY5" smd circle
			(at -33.816544 -5.786628)
			(size 0.4318 0.4318)
			(layers "F.Cu" "F.Mask" "F.Paste")
			(net "GND")
		)
		(pad "AY7" smd circle
			(at -32.099504 -5.786628)
			(size 0.4318 0.4318)
			(layers "F.Cu" "F.Mask" "F.Paste")
			(net "UPI_CPU1_CPU0_P0P0_DP<6>")
		)
		(pad "AY9" smd circle
			(at -30.382464 -5.786628)
			(size 0.4318 0.4318)
			(layers "F.Cu" "F.Mask" "F.Paste")
			(net "UPI_CPU1_CPU0_P0P0_DN<2>")
		)
		(pad "AY11" smd circle
			(at -28.665424 -5.786628)
			(size 0.4318 0.4318)
			(layers "F.Cu" "F.Mask" "F.Paste")
			(net "PVCCIO_CPU0")
		)
		(pad "AY13" smd circle
			(at -26.948384 -5.786628)
			(size 0.4318 0.4318)
			(layers "F.Cu" "F.Mask" "F.Paste")
			(net "TP_CPU0_RSVD_TEST_11")
		)
		(pad "AY15" smd circle
			(at -25.231598 -5.786628)
			(size 0.4318 0.4318)
			(layers "F.Cu" "F.Mask" "F.Paste")
			(net "GND")
		)
		(pad "AY17" smd circle
			(at -23.514558 -5.786628)
			(size 0.4318 0.4318)
			(layers "F.Cu" "F.Mask" "F.Paste")
			(net "GND")
		)
		(pad "AY19" smd circle
			(at -21.797518 -5.786628)
			(size 0.4318 0.4318)
			(layers "F.Cu" "F.Mask" "F.Paste")
			(net "PD_CPU0_TEST12")
		)
		(pad "AY21" smd circle
			(at -20.080478 -5.786628)
			(size 0.4318 0.4318)
			(layers "F.Cu" "F.Mask" "F.Paste")
			(net "GND")
		)
		(pad "AY23" smd circle
			(at -18.363438 -5.786628)
			(size 0.4318 0.4318)
			(layers "F.Cu" "F.Mask" "F.Paste")
			(net "GND")
		)
		(pad "AY25" smd circle
			(at -16.646398 -5.786628)
			(size 0.4318 0.4318)
			(layers "F.Cu" "F.Mask" "F.Paste")
			(net "GND")
		)
		(pad "AY27" smd circle
			(at -14.929612 -5.786628)
			(size 0.4318 0.4318)
			(layers "F.Cu" "F.Mask" "F.Paste")
			(net "PVCCIO_CPU0")
		)
		(pad "AY61" smd circle
			(at 15.787878 -7.586726)
			(size 0.4318 0.4318)
			(layers "F.Cu" "F.Mask" "F.Paste")
			(net "PVCCIN_CPU0")
		)
		(pad "AY63" smd circle
			(at 17.504918 -7.586726)
			(size 0.4318 0.4318)
			(layers "F.Cu" "F.Mask" "F.Paste")
			(net "GND")
		)
		(pad "AY65" smd circle
			(at 19.221958 -7.586726)
			(size 0.4318 0.4318)
			(layers "F.Cu" "F.Mask" "F.Paste")
			(net "TP_CPU0_RSVD_182")
		)
		(pad "AY67" smd circle
			(at 20.938998 -7.586726)
			(size 0.4318 0.4318)
			(layers "F.Cu" "F.Mask" "F.Paste")
			(net "TP_CPU0_RSVD_181")
		)
		(pad "AY69" smd circle
			(at 22.656038 -7.586726)
			(size 0.4318 0.4318)
			(layers "F.Cu" "F.Mask" "F.Paste")
			(net "M_C_ECC<3>")
		)
		(pad "AY71" smd circle
			(at 24.373078 -7.586726)
			(size 0.4318 0.4318)
			(layers "F.Cu" "F.Mask" "F.Paste")
			(net "M_C_DQS_DP<8>")
		)
		(pad "AY73" smd circle
			(at 26.090118 -7.586726)
			(size 0.4318 0.4318)
			(layers "F.Cu" "F.Mask" "F.Paste")
			(net "M_C_ECC<5>")
		)
		(pad "AY75" smd circle
			(at 27.806904 -7.586726)
			(size 0.4318 0.4318)
			(layers "F.Cu" "F.Mask" "F.Paste")
			(net "TP_CPU0_RSVD_180")
		)
		(pad "AY77" smd circle
			(at 29.523944 -7.586726)
			(size 0.4318 0.4318)
			(layers "F.Cu" "F.Mask" "F.Paste")
			(net "TP_CPU0_RSVD_179")
		)
		(pad "AY79" smd circle
			(at 31.240984 -7.586726)
			(size 0.4318 0.4318)
			(layers "F.Cu" "F.Mask" "F.Paste")
			(net "GND")
		)
		(pad "AY81" smd circle
			(at 32.958024 -7.586726)
			(size 0.4318 0.4318)
			(layers "F.Cu" "F.Mask" "F.Paste")
			(net "GND")
		)
		(pad "AY83" smd circle
			(at 34.675064 -7.586726)
			(size 0.4318 0.4318)
			(layers "F.Cu" "F.Mask" "F.Paste")
			(net "TP_CPU0_RSVD_255")
		)
		(pad "AY85" smd circle
			(at 36.392104 -7.586726)
			(size 0.4318 0.4318)
			(layers "F.Cu" "F.Mask" "F.Paste")
			(net "VSENSE_PVCCIN_CPU0_SKT_VRTN")
		)
		(pad "B3" smd custom
			(at -35.533584 -24.608028 45)
			(size 0.10795 0.10795)
			(layers "F.Cu" "F.Mask" "F.Paste")
			(net "TP_CPU0_RSVD_299")
			(options
				(clearance outline)
				(anchor circle)
			)
			(primitives
				(gr_poly
					(pts
						(arc
							(start 0.2159 -0.0381)
							(mid 0 -0.254)
							(end -0.2159 -0.0381)
						)
						(arc
							(start -0.2159 0.0381)
							(mid 0 0.254)
							(end 0.2159 0.0381)
						)
					)
					(width 0)
					(fill yes)
				)
			)
		)
		(pad "B5" smd custom
			(at -33.816544 -24.608028 45)
			(size 0.10795 0.10795)
			(layers "F.Cu" "F.Mask" "F.Paste")
			(net "GND")
			(options
				(clearance outline)
				(anchor circle)
			)
			(primitives
				(gr_poly
					(pts
						(arc
							(start 0.2159 -0.0381)
							(mid 0 -0.254)
							(end -0.2159 -0.0381)
						)
						(arc
							(start -0.2159 0.0381)
							(mid 0 0.254)
							(end 0.2159 0.0381)
						)
					)
					(width 0)
					(fill yes)
				)
			)
		)
		(pad "B7" smd custom
			(at -32.099504 -24.608028)
			(size 0.10795 0.10795)
			(layers "F.Cu" "F.Mask" "F.Paste")
			(net "TP_CPU0_RSVD_298")
			(options
				(clearance outline)
				(anchor circle)
			)
			(primitives
				(gr_poly
					(pts
						(arc
							(start 0.2159 -0.0381)
							(mid 0 -0.254)
							(end -0.2159 -0.0381)
						)
						(arc
							(start -0.2159 0.0381)
							(mid 0 0.254)
							(end 0.2159 0.0381)
						)
					)
					(width 0)
					(fill yes)
				)
			)
		)
		(pad "B9" smd circle
			(at -30.382464 -24.608028)
			(size 0.4318 0.4318)
			(layers "F.Cu" "F.Mask" "F.Paste")
			(net "GND")
		)
	)
)
